(kicad_pcb
	(version 20241229)
	(generator "pcbnew")
	(generator_version "9.0")
	(general
		(thickness 1.552)
		(legacy_teardrops no)
	)
	(paper "A4")
	(title_block
		(date "2023-07-25")
		(rev "1.1.4")
		(comment 9 "footprints 139-143 of 379")
	)
	(layers
		(0 "F.Cu" signal)
		(4 "In1.Cu" signal)
		(6 "In2.Cu" signal)
		(8 "In3.Cu" signal)
		(10 "In4.Cu" signal)
		(12 "In5.Cu" signal)
		(14 "In6.Cu" signal)
		(2 "B.Cu" signal)
		(9 "F.Adhes" user "F.Adhesive")
		(11 "B.Adhes" user "B.Adhesive")
		(13 "F.Paste" user)
		(15 "B.Paste" user)
		(5 "F.SilkS" user "F.Silkscreen")
		(7 "B.SilkS" user "B.Silkscreen")
		(1 "F.Mask" user)
		(3 "B.Mask" user)
		(17 "Dwgs.User" user "User.Drawings")
		(19 "Cmts.User" user "User.Comments")
		(21 "Eco1.User" user "User.Eco1")
		(23 "Eco2.User" user "User.Eco2")
		(25 "Edge.Cuts" user)
		(27 "Margin" user)
		(31 "F.CrtYd" user "F.Courtyard")
		(29 "B.CrtYd" user "B.Courtyard")
		(35 "F.Fab" user)
		(33 "B.Fab" user)
	)
	(footprint "antmicro-footprints:R_0402_1005Metric"
		(layer "F.Cu")
		(at 167.2 90.6 180)
		(descr "Resistor SMD 0402")
		(tags "resistor SMD 0402")
		(property "Reference" "R125"
			(at 3.67 -0.34 180)
			(layer "F.SilkS")
			(effects
				(font
					(size 0.65 0.65)
					(thickness 0.15)
				)
				(justify left bottom)
			)
		)
		(property "Value" "R_0R_0402"
			(at 0 1.4 180)
			(layer "F.Fab")
			(hide yes)
			(effects
				(font
					(size 0.7 0.7)
					(thickness 0.15)
				)
				(justify left bottom)
			)
		)
		(property "Datasheet" "https://industrial.panasonic.com/cdbs/www-data/pdf/RDA0000/AOA0000C301.pdf"
			(at 0 0 180)
			(layer "F.Fab")
			(hide yes)
			(effects
				(font
					(size 1.27 1.27)
					(thickness 0.15)
				)
			)
		)
		(property "Description" "SMD Chip Resistor, Jumper, 0 ohm, 100 mW, 0402 [1005 Metric], Thick Film, General Purpose"
			(at 0 0 180)
			(layer "F.Fab")
			(hide yes)
			(effects
				(font
					(size 1.27 1.27)
					(thickness 0.15)
				)
			)
		)
		(property "Author" "Antmicro"
			(at 334.4 181.2 0)
			(layer "F.Fab")
			(hide yes)
			(effects
				(font
					(size 1 1)
					(thickness 0.15)
				)
			)
		)
		(property "Current" "1A"
			(at 334.4 181.2 0)
			(layer "F.Fab")
			(hide yes)
			(effects
				(font
					(size 1 1)
					(thickness 0.15)
				)
			)
		)
		(property "License" "Apache-2.0"
			(at 334.4 181.2 0)
			(layer "F.Fab")
			(hide yes)
			(effects
				(font
					(size 1 1)
					(thickness 0.15)
				)
			)
		)
		(property "MPN" "ERJ2GE0R00X"
			(at 334.4 181.2 0)
			(layer "F.Fab")
			(hide yes)
			(effects
				(font
					(size 1 1)
					(thickness 0.15)
				)
			)
		)
		(property "Manufacturer" "Panasonic"
			(at 334.4 181.2 0)
			(layer "F.Fab")
			(hide yes)
			(effects
				(font
					(size 1 1)
					(thickness 0.15)
				)
			)
		)
		(property "Tolerance" "~"
			(at 334.4 181.2 0)
			(layer "F.Fab")
			(hide yes)
			(effects
				(font
					(size 1 1)
					(thickness 0.15)
				)
			)
		)
		(property "Val" "0R"
			(at 334.4 181.2 0)
			(layer "F.Fab")
			(hide yes)
			(effects
				(font
					(size 1 1)
					(thickness 0.15)
				)
			)
		)
		(sheetname "/Peripherals/")
		(sheetfile "peripherals.kicad_sch")
		(attr smd)
		(fp_rect
			(start -0.925 -0.47)
			(end 0.925 0.47)
			(stroke
				(width 0.05)
				(type default)
			)
			(fill no)
			(layer "F.CrtYd")
		)
		(fp_rect
			(start -0.5 -0.25)
			(end 0.5 0.25)
			(stroke
				(width 0.15)
				(type solid)
			)
			(fill no)
			(layer "F.Fab")
		)
		(fp_text user "${REFERENCE}"
			(at -0.95 3.168 180)
			(layer "F.Fab")
			(effects
				(font
					(size 0.7 0.7)
					(thickness 0.15)
				)
				(justify left bottom)
			)
		)
		(fp_text user "Author: Antmicro"
			(at -0.95 4.169 180)
			(layer "F.Fab")
			(effects
				(font
					(size 0.7 0.7)
					(thickness 0.15)
				)
				(justify left bottom)
			)
		)
		(fp_text user "License: Apache-2.0"
			(at -0.95 5.169 180)
			(layer "F.Fab")
			(effects
				(font
					(size 0.7 0.7)
					(thickness 0.15)
				)
				(justify left bottom)
			)
		)
		(pad "1" smd roundrect
			(at -0.48 0 180)
			(size 0.59 0.64)
			(layers "F.Cu" "F.Mask" "F.Paste")
			(roundrect_rratio 0.25)
			(net 366 "Net-(J4-Pad42)")
			(pintype "passive")
		)
		(pad "2" smd roundrect
			(at 0.48 0 180)
			(size 0.59 0.64)
			(layers "F.Cu" "F.Mask" "F.Paste")
			(roundrect_rratio 0.25)
			(net 94 "/Peripherals/FCC1_SCL2")
			(pintype "passive")
		)
	)
	(footprint "antmicro-footprints:R_0805_2012Metric"
		(layer "F.Cu")
		(at 159.805 68.55 90)
		(property "Reference" "R17"
			(at -3.99 0.325 90)
			(layer "F.SilkS")
			(effects
				(font
					(size 0.65 0.65)
					(thickness 0.15)
				)
				(justify left bottom)
			)
		)
		(property "Value" "R_0R_0805"
			(at 0 1.8 90)
			(layer "F.Fab")
			(hide yes)
			(effects
				(font
					(size 0.7 0.7)
					(thickness 0.15)
				)
				(justify left bottom)
			)
		)
		(property "Datasheet" "https://www.vishay.com/docs/20035/dcrcwe3.pdf"
			(at 0 0 90)
			(layer "F.Fab")
			(hide yes)
			(effects
				(font
					(size 1.27 1.27)
					(thickness 0.15)
				)
			)
		)
		(property "Description" "Zero Ohm Resistor, Jumper, 0805 [2012 Metric], Thick Film, 125 mW, 2.5 A, Surface Mount Device"
			(at 0 0 90)
			(layer "F.Fab")
			(hide yes)
			(effects
				(font
					(size 1.27 1.27)
					(thickness 0.15)
				)
			)
		)
		(property "Author" "Antmicro"
			(at 228.355 -91.255 0)
			(layer "F.Fab")
			(hide yes)
			(effects
				(font
					(size 1 1)
					(thickness 0.15)
				)
			)
		)
		(property "Current" "2.5A"
			(at 228.355 -91.255 0)
			(layer "F.Fab")
			(hide yes)
			(effects
				(font
					(size 1 1)
					(thickness 0.15)
				)
			)
		)
		(property "License" "Apache-2.0"
			(at 228.355 -91.255 0)
			(layer "F.Fab")
			(hide yes)
			(effects
				(font
					(size 1 1)
					(thickness 0.15)
				)
			)
		)
		(property "MPN" "CRCW08050000Z0EA"
			(at 228.355 -91.255 0)
			(layer "F.Fab")
			(hide yes)
			(effects
				(font
					(size 1 1)
					(thickness 0.15)
				)
			)
		)
		(property "Manufacturer" "Vishay"
			(at 228.355 -91.255 0)
			(layer "F.Fab")
			(hide yes)
			(effects
				(font
					(size 1 1)
					(thickness 0.15)
				)
			)
		)
		(property "Tolerance" "~"
			(at 228.355 -91.255 0)
			(layer "F.Fab")
			(hide yes)
			(effects
				(font
					(size 1 1)
					(thickness 0.15)
				)
			)
		)
		(property "Val" "0R"
			(at 228.355 -91.255 0)
			(layer "F.Fab")
			(hide yes)
			(effects
				(font
					(size 1 1)
					(thickness 0.15)
				)
			)
		)
		(sheetname "/Power Supply/")
		(sheetfile "supply.kicad_sch")
		(attr smd)
		(fp_line
			(start -0.3 -0.701)
			(end 0.298 -0.701)
			(stroke
				(width 0.15)
				(type solid)
			)
			(layer "F.SilkS")
		)
		(fp_line
			(start -0.32 0.699)
			(end 0.28 0.699)
			(stroke
				(width 0.15)
				(type solid)
			)
			(layer "F.SilkS")
		)
		(fp_rect
			(start 1.95 -0.9)
			(end -1.95 0.9)
			(stroke
				(width 0.05)
				(type default)
			)
			(fill no)
			(layer "F.CrtYd")
		)
		(fp_line
			(start -0.951 -0.682)
			(end 0.949 -0.682)
			(stroke
				(width 0.15)
				(type solid)
			)
			(layer "F.Fab")
		)
		(fp_line
			(start 0.949 -0.677)
			(end 0.949 0.675)
			(stroke
				(width 0.15)
				(type solid)
			)
			(layer "F.Fab")
		)
		(fp_line
			(start -0.951 -0.677)
			(end -0.951 0.675)
			(stroke
				(width 0.15)
				(type solid)
			)
			(layer "F.Fab")
		)
		(fp_line
			(start -0.951 0.68)
			(end 0.949 0.68)
			(stroke
				(width 0.15)
				(type solid)
			)
			(layer "F.Fab")
		)
		(fp_text user "License: Apache-2.0"
			(at -1.9 5.75 90)
			(layer "F.Fab")
			(effects
				(font
					(size 0.7 0.7)
					(thickness 0.15)
				)
				(justify left bottom)
			)
		)
		(fp_text user "Author: Antmicro"
			(at -1.9 4.4 90)
			(layer "F.Fab")
			(effects
				(font
					(size 0.7 0.7)
					(thickness 0.15)
				)
				(justify left bottom)
			)
		)
		(fp_text user "${REFERENCE}"
			(at -1.9 3.1 90)
			(layer "F.Fab")
			(effects
				(font
					(size 0.7 0.7)
					(thickness 0.15)
				)
				(justify left bottom)
			)
		)
		(pad "1" smd roundrect
			(at -1.1 0 90)
			(size 1.2 1.3)
			(layers "F.Cu" "F.Mask" "F.Paste")
			(roundrect_rratio 0.25)
			(net 14 "+5V")
			(pintype "passive")
		)
		(pad "2" smd roundrect
			(at 1.1 0 90)
			(size 1.2 1.3)
			(layers "F.Cu" "F.Mask" "F.Paste")
			(roundrect_rratio 0.25)
			(net 328 "/Power Supply/5V_3V3_IN")
			(pintype "passive")
		)
	)
	(footprint "antmicro-footprints:PinHeader_2x5_P1.27mm_SMD_Shrouded"
		(layer "F.Cu")
		(at 101 119.7)
		(property "Reference" "J7"
			(at -6.601 -3.801 0)
			(layer "F.SilkS")
			(effects
				(font
					(size 0.65 0.65)
					(thickness 0.15)
				)
				(justify left bottom)
			)
		)
		(property "Value" "PinHeader_2x5_P2mm_Drill0.71mm_Shrouded"
			(at -6.75 4.75 0)
			(layer "F.Fab")
			(hide yes)
			(effects
				(font
					(size 0.7 0.7)
					(thickness 0.15)
				)
				(justify left bottom)
			)
		)
		(property "Datasheet" "https://eu.mouser.com/datasheet/2/527/shf-1370134.pdf"
			(at 0 0 0)
			(layer "F.Fab")
			(hide yes)
			(effects
				(font
					(size 1.27 1.27)
					(thickness 0.15)
				)
			)
		)
		(property "Description" "Headers & Wire Housings Shrouded Terminal Strip, 0.050\" pitch"
			(at 0 0 0)
			(layer "F.Fab")
			(hide yes)
			(effects
				(font
					(size 1.27 1.27)
					(thickness 0.15)
				)
			)
		)
		(property "Author" "Antmicro"
			(at 0 0 0)
			(layer "F.Fab")
			(hide yes)
			(effects
				(font
					(size 1 1)
					(thickness 0.15)
				)
			)
		)
		(property "License" "Apache-2.0"
			(at 0 0 0)
			(layer "F.Fab")
			(hide yes)
			(effects
				(font
					(size 1 1)
					(thickness 0.15)
				)
			)
		)
		(property "MPN" "SHF-105-01-L-D-SM"
			(at 0 0 0)
			(layer "F.Fab")
			(hide yes)
			(effects
				(font
					(size 1 1)
					(thickness 0.15)
				)
			)
		)
		(property "Manufacturer" "Samtec"
			(at 0 0 0)
			(layer "F.Fab")
			(hide yes)
			(effects
				(font
					(size 1 1)
					(thickness 0.15)
				)
			)
		)
		(sheetname "/FPGA/")
		(sheetfile "fpga.kicad_sch")
		(attr smd)
		(fp_line
			(start -6.415 -2.86)
			(end -3.286 -2.86)
			(stroke
				(width 0.15)
				(type solid)
			)
			(layer "F.SilkS")
		)
		(fp_line
			(start -6.415 2.858)
			(end -6.415 -2.86)
			(stroke
				(width 0.15)
				(type solid)
			)
			(layer "F.SilkS")
		)
		(fp_line
			(start -6.415 2.858)
			(end -3.286 2.858)
			(stroke
				(width 0.15)
				(type solid)
			)
			(layer "F.SilkS")
		)
		(fp_line
			(start 3.285 -2.86)
			(end 6.413 -2.86)
			(stroke
				(width 0.15)
				(type solid)
			)
			(layer "F.SilkS")
		)
		(fp_line
			(start 3.285 2.858)
			(end 6.413 2.858)
			(stroke
				(width 0.15)
				(type solid)
			)
			(layer "F.SilkS")
		)
		(fp_line
			(start 6.413 2.858)
			(end 6.413 -2.86)
			(stroke
				(width 0.15)
				(type solid)
			)
			(layer "F.SilkS")
		)
		(fp_rect
			(start -6.601 -3.498)
			(end 6.599 3.547)
			(stroke
				(width 0.05)
				(type solid)
			)
			(fill no)
			(layer "F.CrtYd")
		)
		(fp_line
			(start -6.415 -2.86)
			(end 6.413 -2.86)
			(stroke
				(width 0.15)
				(type solid)
			)
			(layer "F.Fab")
		)
		(fp_line
			(start -6.415 2.858)
			(end -6.415 -2.86)
			(stroke
				(width 0.15)
				(type solid)
			)
			(layer "F.Fab")
		)
		(fp_line
			(start 6.413 -2.86)
			(end 6.413 2.858)
			(stroke
				(width 0.15)
				(type solid)
			)
			(layer "F.Fab")
		)
		(fp_line
			(start 6.413 2.858)
			(end -6.415 2.858)
			(stroke
				(width 0.15)
				(type solid)
			)
			(layer "F.Fab")
		)
		(pad "1" smd rect
			(at -2.54 2.055)
			(size 0.74 2.795)
			(layers "F.Cu" "F.Mask" "F.Paste")
			(net 2 "+3V3")
			(pinfunction "1")
			(pintype "passive")
		)
		(pad "2" smd rect
			(at -2.54 -2.009)
			(size 0.74 2.795)
			(layers "F.Cu" "F.Mask" "F.Paste")
			(net 134 "Net-(J7-Pad2)")
			(pinfunction "2")
			(pintype "passive")
		)
		(pad "3" smd rect
			(at -1.27 2.055)
			(size 0.74 2.795)
			(layers "F.Cu" "F.Mask" "F.Paste")
			(net 1 "GND")
			(pinfunction "3")
			(pintype "passive")
		)
		(pad "4" smd rect
			(at -1.27 -2.009)
			(size 0.74 2.795)
			(layers "F.Cu" "F.Mask" "F.Paste")
			(net 135 "Net-(J7-Pad4)")
			(pinfunction "4")
			(pintype "passive")
		)
		(pad "5" smd rect
			(at 0 2.055)
			(size 0.74 2.795)
			(layers "F.Cu" "F.Mask" "F.Paste")
			(net 1 "GND")
			(pinfunction "5")
			(pintype "passive")
		)
		(pad "6" smd rect
			(at 0 -2.009)
			(size 0.74 2.795)
			(layers "F.Cu" "F.Mask" "F.Paste")
			(net 136 "Net-(J7-Pad6)")
			(pinfunction "6")
			(pintype "passive")
		)
		(pad "7" smd rect
			(at 1.269 2.055)
			(size 0.74 2.795)
			(layers "F.Cu" "F.Mask" "F.Paste")
			(net 137 "unconnected-(J7-Pad7)")
			(pinfunction "7")
			(pintype "passive+no_connect")
		)
		(pad "8" smd rect
			(at 1.269 -2.009)
			(size 0.74 2.795)
			(layers "F.Cu" "F.Mask" "F.Paste")
			(net 138 "Net-(J7-Pad8)")
			(pinfunction "8")
			(pintype "passive")
		)
		(pad "9" smd rect
			(at 2.539 2.055)
			(size 0.74 2.795)
			(layers "F.Cu" "F.Mask" "F.Paste")
			(net 1 "GND")
			(pinfunction "9")
			(pintype "passive")
		)
		(pad "10" smd rect
			(at 2.539 -2.009)
			(size 0.74 2.795)
			(layers "F.Cu" "F.Mask" "F.Paste")
			(net 139 "Net-(J7-Pad10)")
			(pinfunction "10")
			(pintype "passive")
		)
	)
	(footprint "antmicro-footprints:R_0402_1005Metric"
		(layer "F.Cu")
		(at 101.2 102.7 -90)
		(descr "Resistor SMD 0402")
		(tags "resistor SMD 0402")
		(property "Reference" "R66"
			(at 1.04 -0.33 90)
			(layer "F.SilkS")
			(effects
				(font
					(size 0.65 0.65)
					(thickness 0.15)
				)
				(justify right bottom)
			)
		)
		(property "Value" "R_0R_0402"
			(at 0 1.4 90)
			(layer "F.Fab")
			(hide yes)
			(effects
				(font
					(size 0.7 0.7)
					(thickness 0.15)
				)
				(justify right bottom)
			)
		)
		(property "Datasheet" "https://industrial.panasonic.com/cdbs/www-data/pdf/RDA0000/AOA0000C301.pdf"
			(at 0 0 270)
			(layer "F.Fab")
			(hide yes)
			(effects
				(font
					(size 1.27 1.27)
					(thickness 0.15)
				)
			)
		)
		(property "Description" "SMD Chip Resistor, Jumper, 0 ohm, 100 mW, 0402 [1005 Metric], Thick Film, General Purpose"
			(at 0 0 270)
			(layer "F.Fab")
			(hide yes)
			(effects
				(font
					(size 1.27 1.27)
					(thickness 0.15)
				)
			)
		)
		(property "Author" "Antmicro"
			(at -1.5 203.9 0)
			(layer "F.Fab")
			(hide yes)
			(effects
				(font
					(size 1 1)
					(thickness 0.15)
				)
			)
		)
		(property "Current" "1A"
			(at -1.5 203.9 0)
			(layer "F.Fab")
			(hide yes)
			(effects
				(font
					(size 1 1)
					(thickness 0.15)
				)
			)
		)
		(property "License" "Apache-2.0"
			(at -1.5 203.9 0)
			(layer "F.Fab")
			(hide yes)
			(effects
				(font
					(size 1 1)
					(thickness 0.15)
				)
			)
		)
		(property "MPN" "ERJ2GE0R00X"
			(at -1.5 203.9 0)
			(layer "F.Fab")
			(hide yes)
			(effects
				(font
					(size 1 1)
					(thickness 0.15)
				)
			)
		)
		(property "Manufacturer" "Panasonic"
			(at -1.5 203.9 0)
			(layer "F.Fab")
			(hide yes)
			(effects
				(font
					(size 1 1)
					(thickness 0.15)
				)
			)
		)
		(property "Tolerance" "~"
			(at -1.5 203.9 0)
			(layer "F.Fab")
			(hide yes)
			(effects
				(font
					(size 1 1)
					(thickness 0.15)
				)
			)
		)
		(property "Val" "0R"
			(at -1.5 203.9 0)
			(layer "F.Fab")
			(hide yes)
			(effects
				(font
					(size 1 1)
					(thickness 0.15)
				)
			)
		)
		(sheetname "/FPGA/")
		(sheetfile "fpga.kicad_sch")
		(attr smd)
		(fp_rect
			(start -0.925 -0.47)
			(end 0.925 0.47)
			(stroke
				(width 0.05)
				(type default)
			)
			(fill no)
			(layer "F.CrtYd")
		)
		(fp_rect
			(start -0.5 -0.25)
			(end 0.5 0.25)
			(stroke
				(width 0.15)
				(type solid)
			)
			(fill no)
			(layer "F.Fab")
		)
		(fp_text user "${REFERENCE}"
			(at -0.95 3.168 270)
			(layer "F.Fab")
			(effects
				(font
					(size 0.7 0.7)
					(thickness 0.15)
				)
				(justify left bottom)
			)
		)
		(fp_text user "License: Apache-2.0"
			(at -0.95 5.169 270)
			(layer "F.Fab")
			(effects
				(font
					(size 0.7 0.7)
					(thickness 0.15)
				)
				(justify left bottom)
			)
		)
		(fp_text user "Author: Antmicro"
			(at -0.95 4.169 270)
			(layer "F.Fab")
			(effects
				(font
					(size 0.7 0.7)
					(thickness 0.15)
				)
				(justify left bottom)
			)
		)
		(pad "1" smd roundrect
			(at -0.48 0 270)
			(size 0.59 0.64)
			(layers "F.Cu" "F.Mask" "F.Paste")
			(roundrect_rratio 0.25)
			(net 299 "Net-(U17-~{RESET})")
			(pintype "passive")
		)
		(pad "2" smd roundrect
			(at 0.48 0 270)
			(size 0.59 0.64)
			(layers "F.Cu" "F.Mask" "F.Paste")
			(roundrect_rratio 0.25)
			(net 2 "+3V3")
			(pintype "passive")
		)
	)
	(footprint "antmicro-footprints:R_0402_1005Metric"
		(layer "F.Cu")
		(at 102.94 115.185 90)
		(descr "Resistor SMD 0402")
		(tags "resistor SMD 0402")
		(property "Reference" "R96"
			(at 0.895 0.39 90)
			(layer "F.SilkS")
			(effects
				(font
					(size 0.65 0.65)
					(thickness 0.15)
				)
				(justify left bottom)
			)
		)
		(property "Value" "R_0R_0402"
			(at 0 1.4 90)
			(layer "F.Fab")
			(hide yes)
			(effects
				(font
					(size 0.7 0.7)
					(thickness 0.15)
				)
				(justify left bottom)
			)
		)
		(property "Datasheet" "https://industrial.panasonic.com/cdbs/www-data/pdf/RDA0000/AOA0000C301.pdf"
			(at 0 0 90)
			(layer "F.Fab")
			(hide yes)
			(effects
				(font
					(size 1.27 1.27)
					(thickness 0.15)
				)
			)
		)
		(property "Description" "SMD Chip Resistor, Jumper, 0 ohm, 100 mW, 0402 [1005 Metric], Thick Film, General Purpose"
			(at 0 0 90)
			(layer "F.Fab")
			(hide yes)
			(effects
				(font
					(size 1.27 1.27)
					(thickness 0.15)
				)
			)
		)
		(property "Author" "Antmicro"
			(at 218.125 12.245 0)
			(layer "F.Fab")
			(hide yes)
			(effects
				(font
					(size 1 1)
					(thickness 0.15)
				)
			)
		)
		(property "Current" "1A"
			(at 218.125 12.245 0)
			(layer "F.Fab")
			(hide yes)
			(effects
				(font
					(size 1 1)
					(thickness 0.15)
				)
			)
		)
		(property "License" "Apache-2.0"
			(at 218.125 12.245 0)
			(layer "F.Fab")
			(hide yes)
			(effects
				(font
					(size 1 1)
					(thickness 0.15)
				)
			)
		)
		(property "MPN" "ERJ2GE0R00X"
			(at 218.125 12.245 0)
			(layer "F.Fab")
			(hide yes)
			(effects
				(font
					(size 1 1)
					(thickness 0.15)
				)
			)
		)
		(property "Manufacturer" "Panasonic"
			(at 218.125 12.245 0)
			(layer "F.Fab")
			(hide yes)
			(effects
				(font
					(size 1 1)
					(thickness 0.15)
				)
			)
		)
		(property "Tolerance" "~"
			(at 218.125 12.245 0)
			(layer "F.Fab")
			(hide yes)
			(effects
				(font
					(size 1 1)
					(thickness 0.15)
				)
			)
		)
		(property "Val" "0R"
			(at 218.125 12.245 0)
			(layer "F.Fab")
			(hide yes)
			(effects
				(font
					(size 1 1)
					(thickness 0.15)
				)
			)
		)
		(sheetname "/FPGA/")
		(sheetfile "fpga.kicad_sch")
		(attr smd)
		(fp_rect
			(start -0.925 -0.47)
			(end 0.925 0.47)
			(stroke
				(width 0.05)
				(type default)
			)
			(fill no)
			(layer "F.CrtYd")
		)
		(fp_rect
			(start -0.5 -0.25)
			(end 0.5 0.25)
			(stroke
				(width 0.15)
				(type solid)
			)
			(fill no)
			(layer "F.Fab")
		)
		(fp_text user "License: Apache-2.0"
			(at -0.95 5.169 90)
			(layer "F.Fab")
			(effects
				(font
					(size 0.7 0.7)
					(thickness 0.15)
				)
				(justify left bottom)
			)
		)
		(fp_text user "${REFERENCE}"
			(at -0.95 3.168 90)
			(layer "F.Fab")
			(effects
				(font
					(size 0.7 0.7)
					(thickness 0.15)
				)
				(justify left bottom)
			)
		)
		(fp_text user "Author: Antmicro"
			(at -0.95 4.169 90)
			(layer "F.Fab")
			(effects
				(font
					(size 0.7 0.7)
					(thickness 0.15)
				)
				(justify left bottom)
			)
		)
		(pad "1" smd roundrect
			(at -0.48 0 90)
			(size 0.59 0.64)
			(layers "F.Cu" "F.Mask" "F.Paste")
			(roundrect_rratio 0.25)
			(net 139 "Net-(J7-Pad10)")
			(pintype "passive")
		)
		(pad "2" smd roundrect
			(at 0.48 0 90)
			(size 0.59 0.64)
			(layers "F.Cu" "F.Mask" "F.Paste")
			(roundrect_rratio 0.25)
			(net 173 "JTAG_EN")
			(pintype "passive")
		)
	)
)
